# S9S_MB_2U (Grand Teton) — schematic netlist excerpt (pin names and nets, part order shuffled) for the footprints in the layout excerpt that follows; sources: Cadence DE-HDL packaged netlist, KiCad conversion of 03242023_DA0F0TMBIJ0_F0T_Motherboard_J_brd_V01_OCP.brd

C751  Q_CAP_DIFFBUS  DIFF BUS_0.22UF 6.3V 20% X6S  pkg C0201  page 176 : \1\ = P5E_CPU1_PE2_TX_C_DP<11> ; \2\ = P5E_CPU1_PE2_TX_DP<11>

PU82  RS53317LR  IC  pkg QFN14_0-5_3X2XB  page 300
  PGND1  = GND
  SW1  = SW_PVNN_MAIN_CPU1_SW
  VIN  = SW_P12V_PVCCINFAON_CPU1_FLT
  CS  = PVNN_MAIN_CPU1_CS
  EN  = FM_PVNN_MAIN_CPU1_EN
  FB  = PVNN_MAIN_CPU1_FB
  AGND  = GND
  REF  = PVNN_MAIN_CPU1_REF
  PGOOD  = PWRGD_PVNN_MAIN_CPU1_R
  BST  = SW_PVNN_MAIN_CPU1_BST
  SW2  = SW_PVNN_MAIN_CPU1_SW
  MODE  = PVNN_MAIN_CPU1_MODE
  VCC  = PVNN_MAIN_CPU1_VCC
  PGND2  = GND

(kicad_pcb
	(version 20260206)
	(generator "pcbnew")
	(generator_version "10.0")
	(general
		(thickness 1.6)
		(legacy_teardrops no)
	)
	(paper "A4")
	(title_block
		(title "03242023_DA0F0TMBIJ0_F0T_Motherboard_J_brd_V01_OCP.brd")
		(comment 1 "Grand Teton / footprints 3596-3597 of 6105")
	)
	(layers
		(0 "F.Cu" signal "TOP")
		(4 "In1.Cu" signal "GND")
		(6 "In2.Cu" signal "IN1")
		(8 "In3.Cu" signal "GND1")
		(10 "In4.Cu" signal "IN2")
		(12 "In5.Cu" signal "GND2")
		(14 "In6.Cu" signal "IN3")
		(16 "In7.Cu" signal "GND3")
		(18 "In8.Cu" signal "VCC")
		(20 "In9.Cu" signal "VCC1")
		(22 "In10.Cu" signal "GND4")
		(24 "In11.Cu" signal "IN4")
		(26 "In12.Cu" signal "GND5")
		(28 "In13.Cu" signal "IN5")
		(30 "In14.Cu" signal "GND6")
		(32 "In15.Cu" signal "IN6")
		(34 "In16.Cu" signal "GND7")
		(2 "B.Cu" signal "BOTTOM")
		(9 "F.Adhes" user "F.Adhesive")
		(11 "B.Adhes" user "B.Adhesive")
		(13 "F.Paste" user "Package Geometry/Pastemask Top")
		(15 "B.Paste" user "Package Geometry/Pastemask Bottom")
		(5 "F.SilkS" user "Ref Des/Silkscreen Top")
		(7 "B.SilkS" user "Ref Des/Silkscreen Bottom")
		(1 "F.Mask" user "Board Geometry/Soldermask Top")
		(3 "B.Mask" user "Board Geometry/Soldermask Bottom")
		(17 "Dwgs.User" user "User.Drawings")
		(19 "Cmts.User" user "User.Comments")
		(21 "Eco1.User" user "User.Eco1")
		(23 "Eco2.User" user "User.Eco2")
		(25 "Edge.Cuts" user "Board Geometry/Outline")
		(27 "Margin" user)
		(31 "F.CrtYd" user "Package Geometry/Place Bound Top")
		(29 "B.CrtYd" user "Package Geometry/Place Bound Bottom")
		(35 "F.Fab" user "Ref Des/Assembly Top")
		(33 "B.Fab" user "Ref Des/Assembly Bottom")
	)
	(footprint ""
		(layer "F.Cu")
		(at 23.10511 -179.928266)
		(property "Reference" "PU82"
			(at -4.4704 7.05358 0)
			(unlocked yes)
			(layer "F.SilkS")
			(effects
				(font
					(size 0.7874 0.5842)
					(thickness 0.1524)
				)
				(justify left)
			)
		)
		(property "Value" ""
			(at 0 0 0)
			(layer "F.Fab")
			(effects
				(font
					(size 1.27 1.27)
				)
			)
		)
		(duplicate_pad_numbers_are_jumpers no)
		(fp_line
			(start -1.050036 -1.549908)
			(end -0.503936 -1.549908)
			(stroke
				(width 0.1524)
				(type default)
			)
			(layer "F.SilkS")
		)
		(fp_line
			(start -1.050036 -1.253998)
			(end -1.050036 -1.549908)
			(stroke
				(width 0.1524)
				(type default)
			)
			(layer "F.SilkS")
		)
		(fp_line
			(start -1.050036 1.549908)
			(end -1.050036 1.253998)
			(stroke
				(width 0.1524)
				(type default)
			)
			(layer "F.SilkS")
		)
		(fp_line
			(start -0.503936 1.549908)
			(end -1.050036 1.549908)
			(stroke
				(width 0.1524)
				(type default)
			)
			(layer "F.SilkS")
		)
		(fp_line
			(start 0.503936 -1.549908)
			(end 1.050036 -1.549908)
			(stroke
				(width 0.1524)
				(type default)
			)
			(layer "F.SilkS")
		)
		(fp_line
			(start 1.050036 -1.549908)
			(end 1.050036 -1.253998)
			(stroke
				(width 0.1524)
				(type default)
			)
			(layer "F.SilkS")
		)
		(fp_line
			(start 1.050036 1.253998)
			(end 1.050036 1.549908)
			(stroke
				(width 0.1524)
				(type default)
			)
			(layer "F.SilkS")
		)
		(fp_line
			(start 1.050036 1.549908)
			(end 0.503936 1.549908)
			(stroke
				(width 0.1524)
				(type default)
			)
			(layer "F.SilkS")
		)
		(fp_poly
			(pts
				(xy -1.474724 -2.460498) (xy -1.385824 -1.613154) (xy -2.11709 -2.050288)
			)
			(stroke
				(width 0)
				(type default)
			)
			(fill yes)
			(layer "F.SilkS")
		)
		(fp_line
			(start -1.050036 -1.549908)
			(end 1.050036 -1.549908)
			(stroke
				(width 0.1)
				(type default)
			)
			(layer "F.Fab")
		)
		(fp_line
			(start -1.050036 1.549908)
			(end -1.050036 -1.549908)
			(stroke
				(width 0.1)
				(type default)
			)
			(layer "F.Fab")
		)
		(fp_line
			(start 1.050036 -1.549908)
			(end 1.050036 1.549908)
			(stroke
				(width 0.1)
				(type default)
			)
			(layer "F.Fab")
		)
		(fp_line
			(start 1.050036 1.549908)
			(end -1.050036 1.549908)
			(stroke
				(width 0.1)
				(type default)
			)
			(layer "F.Fab")
		)
		(fp_poly
			(pts
				(xy -2.2352 -0.618998) (xy -2.2352 -1.380998) (xy -1.4732 -0.999998)
			)
			(stroke
				(width 0)
				(type default)
			)
			(fill yes)
			(layer "F.Fab")
		)
		(pad "1" smd circle
			(at -0.94996 -0.999998 270)
			(size 0 0)
			(layers "F.Cu" "F.Mask" "F.Paste")
			(net "GND")
		)
		(pad "2" smd rect
			(at -0.849884 -0.499872 90)
			(size 0.254 0.9144)
			(layers "F.Cu" "F.Mask" "F.Paste")
			(net "SW_PVNN_MAIN_CPU1_SW")
		)
		(pad "3" smd rect
			(at -0.649986 0 90)
			(size 0.254 1.3208)
			(layers "F.Cu" "F.Mask" "F.Paste")
			(net "SW_P12V_PVCCINFAON_CPU1_FLT")
		)
		(pad "4" smd rect
			(at -0.849884 0.499872 90)
			(size 0.254 0.9144)
			(layers "F.Cu" "F.Mask" "F.Paste")
			(net "PVNN_MAIN_CPU1_CS")
		)
		(pad "5" smd circle
			(at -0.94996 0.999998 270)
			(size 0 0)
			(layers "F.Cu" "F.Mask" "F.Paste")
			(net "FM_PVNN_MAIN_CPU1_EN")
		)
		(pad "6" smd circle
			(at -0.249936 1.450086)
			(size 0 0)
			(layers "F.Cu" "F.Mask" "F.Paste")
			(net "PVNN_MAIN_CPU1_FB")
		)
		(pad "7" smd circle
			(at 0.249936 1.450086)
			(size 0 0)
			(layers "F.Cu" "F.Mask" "F.Paste")
			(net "GND")
		)
		(pad "8" smd circle
			(at 0.94996 0.999998 90)
			(size 0 0)
			(layers "F.Cu" "F.Mask" "F.Paste")
			(net "PVNN_MAIN_CPU1_REF")
		)
		(pad "9" smd rect
			(at 0.849884 0.499872 90)
			(size 0.254 0.9144)
			(layers "F.Cu" "F.Mask" "F.Paste")
			(net "PWRGD_PVNN_MAIN_CPU1_R")
		)
		(pad "10" smd rect
			(at 0.849884 0 90)
			(size 0.254 0.9144)
			(layers "F.Cu" "F.Mask" "F.Paste")
			(net "SW_PVNN_MAIN_CPU1_BST")
		)
		(pad "11" smd rect
			(at 0.849884 -0.499872 90)
			(size 0.254 0.9144)
			(layers "F.Cu" "F.Mask" "F.Paste")
			(net "SW_PVNN_MAIN_CPU1_SW")
		)
		(pad "12" smd circle
			(at 0.94996 -0.999998 90)
			(size 0 0)
			(layers "F.Cu" "F.Mask" "F.Paste")
			(net "PVNN_MAIN_CPU1_MODE")
		)
		(pad "13" smd circle
			(at 0.249936 -1.450086 180)
			(size 0 0)
			(layers "F.Cu" "F.Mask" "F.Paste")
			(net "PVNN_MAIN_CPU1_VCC")
		)
		(pad "14" smd circle
			(at -0.249936 -1.450086 180)
			(size 0 0)
			(layers "F.Cu" "F.Mask" "F.Paste")
			(net "GND")
		)
	)
	(footprint ""
		(layer "F.Cu")
		(at 132.382514 -402.371052 -90)
		(property "Reference" "C751"
			(at 0 0 270)
			(layer "F.SilkS")
			(hide yes)
			(effects
				(font
					(size 1.27 1.27)
				)
			)
		)
		(property "Value" ""
			(at 0 0 270)
			(layer "F.Fab")
			(effects
				(font
					(size 1.27 1.27)
				)
			)
		)
		(duplicate_pad_numbers_are_jumpers no)
		(fp_line
			(start -0.299974 0.150114)
			(end -0.299974 -0.150114)
			(stroke
				(width 0.1)
				(type default)
			)
			(layer "F.Fab")
		)
		(fp_line
			(start 0.299974 0.150114)
			(end -0.299974 0.150114)
			(stroke
				(width 0.1)
				(type default)
			)
			(layer "F.Fab")
		)
		(fp_line
			(start -0.299974 -0.150114)
			(end 0.299974 -0.150114)
			(stroke
				(width 0.1)
				(type default)
			)
			(layer "F.Fab")
		)
		(fp_line
			(start 0.299974 -0.150114)
			(end 0.299974 0.150114)
			(stroke
				(width 0.1)
				(type default)
			)
			(layer "F.Fab")
		)
		(pad "1" smd rect
			(at -0.2667 0 270)
			(size 0.3048 0.381)
			(layers "F.Cu" "F.Mask" "F.Paste")
			(net "P5E_CPU1_PE2_TX_C_DP<11>")
		)
		(pad "2" smd rect
			(at 0.2667 0 270)
			(size 0.3048 0.381)
			(layers "F.Cu" "F.Mask" "F.Paste")
			(net "P5E_CPU1_PE2_TX_DP<11>")
		)
	)
)
